(kicad_pcb
	(version 20260206)
	(generator "pcbnew")
	(generator_version "10.0")
	(general
		(thickness 1.6)
		(legacy_teardrops no)
	)
	(paper "A4")
	(title_block
		(title "9052_F0T_PDB_Converter_Brick_F_V03_1208_1600_OCP.brd")
		(comment 1 "Grand Teton / footprints 427-432 of 578")
	)
	(layers
		(0 "F.Cu" signal "TOP")
		(4 "In1.Cu" signal "GND")
		(6 "In2.Cu" signal "IN1")
		(8 "In3.Cu" signal "GND1")
		(10 "In4.Cu" signal "VCC")
		(12 "In5.Cu" signal "VCC1")
		(14 "In6.Cu" signal "GND2")
		(16 "In7.Cu" signal "IN2")
		(18 "In8.Cu" signal "GND3")
		(2 "B.Cu" signal "BOTTOM")
		(9 "F.Adhes" user "F.Adhesive")
		(11 "B.Adhes" user "B.Adhesive")
		(13 "F.Paste" user "Package Geometry/Pastemask Top")
		(15 "B.Paste" user "Package Geometry/Pastemask Bottom")
		(5 "F.SilkS" user "Ref Des/Silkscreen Top")
		(7 "B.SilkS" user "Ref Des/Silkscreen Bottom")
		(1 "F.Mask" user "Board Geometry/Soldermask Top")
		(3 "B.Mask" user "Board Geometry/Soldermask Bottom")
		(17 "Dwgs.User" user "User.Drawings")
		(19 "Cmts.User" user "User.Comments")
		(21 "Eco1.User" user "User.Eco1")
		(23 "Eco2.User" user "User.Eco2")
		(25 "Edge.Cuts" user "Board Geometry/Outline")
		(27 "Margin" user)
		(31 "F.CrtYd" user "Package Geometry/Place Bound Top")
		(29 "B.CrtYd" user "Package Geometry/Place Bound Bottom")
		(35 "F.Fab" user "Ref Des/Assembly Top")
		(33 "B.Fab" user "Ref Des/Assembly Bottom")
	)
	(footprint ""
		(layer "B.Cu")
		(at 221.996 -90.043 90)
		(property "Reference" "R36"
			(at 0 0 90)
			(layer "B.SilkS")
			(hide yes)
			(effects
				(font
					(size 1.27 1.27)
				)
				(justify mirror)
			)
		)
		(property "Value" ""
			(at 0 0 90)
			(layer "B.Fab")
			(effects
				(font
					(size 1.27 1.27)
				)
				(justify mirror)
			)
		)
		(duplicate_pad_numbers_are_jumpers no)
		(fp_line
			(start 0.7874 -0.4064)
			(end -0.7874 -0.4064)
			(stroke
				(width 0.1524)
				(type default)
			)
			(layer "B.SilkS")
		)
		(fp_line
			(start -0.7874 -0.4064)
			(end -0.7874 0.4064)
			(stroke
				(width 0.1524)
				(type default)
			)
			(layer "B.SilkS")
		)
		(fp_line
			(start 0.7874 0.4064)
			(end 0.7874 -0.4064)
			(stroke
				(width 0.1524)
				(type default)
			)
			(layer "B.SilkS")
		)
		(fp_line
			(start -0.7874 0.4064)
			(end 0.7874 0.4064)
			(stroke
				(width 0.1524)
				(type default)
			)
			(layer "B.SilkS")
		)
		(fp_line
			(start 0.67945 -0.305054)
			(end 0.12065 -0.305054)
			(stroke
				(width 0.1)
				(type default)
			)
			(layer "B.Fab")
		)
		(fp_line
			(start 0.12065 -0.305054)
			(end 0.12065 -0.2794)
			(stroke
				(width 0.1)
				(type default)
			)
			(layer "B.Fab")
		)
		(fp_line
			(start -0.12065 -0.3048)
			(end -0.67945 -0.3048)
			(stroke
				(width 0.1)
				(type default)
			)
			(layer "B.Fab")
		)
		(fp_line
			(start -0.67945 -0.3048)
			(end -0.67945 0.3048)
			(stroke
				(width 0.1)
				(type default)
			)
			(layer "B.Fab")
		)
		(fp_line
			(start 0.12065 -0.2794)
			(end -0.12065 -0.2794)
			(stroke
				(width 0.1)
				(type default)
			)
			(layer "B.Fab")
		)
		(fp_line
			(start -0.12065 -0.2794)
			(end -0.12065 -0.3048)
			(stroke
				(width 0.1)
				(type default)
			)
			(layer "B.Fab")
		)
		(fp_line
			(start 0.12065 0.2794)
			(end 0.12065 0.3048)
			(stroke
				(width 0.1)
				(type default)
			)
			(layer "B.Fab")
		)
		(fp_line
			(start -0.120396 0.2794)
			(end 0.12065 0.2794)
			(stroke
				(width 0.1)
				(type default)
			)
			(layer "B.Fab")
		)
		(fp_line
			(start 0.67945 0.3048)
			(end 0.67945 -0.305054)
			(stroke
				(width 0.1)
				(type default)
			)
			(layer "B.Fab")
		)
		(fp_line
			(start 0.12065 0.3048)
			(end 0.67945 0.3048)
			(stroke
				(width 0.1)
				(type default)
			)
			(layer "B.Fab")
		)
		(fp_line
			(start -0.120396 0.3048)
			(end -0.120396 0.2794)
			(stroke
				(width 0.1)
				(type default)
			)
			(layer "B.Fab")
		)
		(fp_line
			(start -0.67945 0.3048)
			(end -0.120396 0.3048)
			(stroke
				(width 0.1)
				(type default)
			)
			(layer "B.Fab")
		)
		(pad "1" smd circle
			(at 0.40005 0 270)
			(size 0 0)
			(layers "B.Cu" "B.Mask" "B.Paste")
			(net "P3V3_AUX")
		)
		(pad "2" smd circle
			(at -0.40005 0 270)
			(size 0 0)
			(layers "B.Cu" "B.Mask" "B.Paste")
			(net "FRU_WP_N")
		)
	)
	(footprint ""
		(layer "B.Cu")
		(at 291.27704 -43.13428 90)
		(property "Reference" "R5911"
			(at 0 0 90)
			(layer "B.SilkS")
			(hide yes)
			(effects
				(font
					(size 1.27 1.27)
				)
				(justify mirror)
			)
		)
		(property "Value" ""
			(at 0 0 90)
			(layer "B.Fab")
			(effects
				(font
					(size 1.27 1.27)
				)
				(justify mirror)
			)
		)
		(duplicate_pad_numbers_are_jumpers no)
		(fp_line
			(start 0.7874 -0.4064)
			(end -0.7874 -0.4064)
			(stroke
				(width 0.1524)
				(type default)
			)
			(layer "B.SilkS")
		)
		(fp_line
			(start -0.7874 -0.4064)
			(end -0.7874 0.4064)
			(stroke
				(width 0.1524)
				(type default)
			)
			(layer "B.SilkS")
		)
		(fp_line
			(start 0.7874 0.4064)
			(end 0.7874 -0.4064)
			(stroke
				(width 0.1524)
				(type default)
			)
			(layer "B.SilkS")
		)
		(fp_line
			(start -0.7874 0.4064)
			(end 0.7874 0.4064)
			(stroke
				(width 0.1524)
				(type default)
			)
			(layer "B.SilkS")
		)
		(fp_line
			(start 0.67945 -0.305054)
			(end 0.12065 -0.305054)
			(stroke
				(width 0.1)
				(type default)
			)
			(layer "B.Fab")
		)
		(fp_line
			(start 0.12065 -0.305054)
			(end 0.12065 -0.2794)
			(stroke
				(width 0.1)
				(type default)
			)
			(layer "B.Fab")
		)
		(fp_line
			(start -0.12065 -0.3048)
			(end -0.67945 -0.3048)
			(stroke
				(width 0.1)
				(type default)
			)
			(layer "B.Fab")
		)
		(fp_line
			(start -0.67945 -0.3048)
			(end -0.67945 0.3048)
			(stroke
				(width 0.1)
				(type default)
			)
			(layer "B.Fab")
		)
		(fp_line
			(start 0.12065 -0.2794)
			(end -0.12065 -0.2794)
			(stroke
				(width 0.1)
				(type default)
			)
			(layer "B.Fab")
		)
		(fp_line
			(start -0.12065 -0.2794)
			(end -0.12065 -0.3048)
			(stroke
				(width 0.1)
				(type default)
			)
			(layer "B.Fab")
		)
		(fp_line
			(start 0.12065 0.2794)
			(end 0.12065 0.3048)
			(stroke
				(width 0.1)
				(type default)
			)
			(layer "B.Fab")
		)
		(fp_line
			(start -0.120396 0.2794)
			(end 0.12065 0.2794)
			(stroke
				(width 0.1)
				(type default)
			)
			(layer "B.Fab")
		)
		(fp_line
			(start 0.67945 0.3048)
			(end 0.67945 -0.305054)
			(stroke
				(width 0.1)
				(type default)
			)
			(layer "B.Fab")
		)
		(fp_line
			(start 0.12065 0.3048)
			(end 0.67945 0.3048)
			(stroke
				(width 0.1)
				(type default)
			)
			(layer "B.Fab")
		)
		(fp_line
			(start -0.120396 0.3048)
			(end -0.120396 0.2794)
			(stroke
				(width 0.1)
				(type default)
			)
			(layer "B.Fab")
		)
		(fp_line
			(start -0.67945 0.3048)
			(end -0.120396 0.3048)
			(stroke
				(width 0.1)
				(type default)
			)
			(layer "B.Fab")
		)
		(pad "1" smd circle
			(at 0.40005 0 270)
			(size 0 0)
			(layers "B.Cu" "B.Mask" "B.Paste")
			(net "FM_AC_PWR_CYCLE_N")
		)
		(pad "2" smd circle
			(at -0.40005 0 270)
			(size 0 0)
			(layers "B.Cu" "B.Mask" "B.Paste")
			(net "GND")
		)
	)
	(footprint ""
		(layer "B.Cu")
		(at 228.219 -70.993 -90)
		(property "Reference" "R96"
			(at 0 0 90)
			(layer "B.SilkS")
			(hide yes)
			(effects
				(font
					(size 1.27 1.27)
				)
				(justify mirror)
			)
		)
		(property "Value" ""
			(at 0 0 90)
			(layer "B.Fab")
			(effects
				(font
					(size 1.27 1.27)
				)
				(justify mirror)
			)
		)
		(duplicate_pad_numbers_are_jumpers no)
		(fp_line
			(start -0.7874 0.4064)
			(end 0.7874 0.4064)
			(stroke
				(width 0.1524)
				(type default)
			)
			(layer "B.SilkS")
		)
		(fp_line
			(start 0.7874 0.4064)
			(end 0.7874 -0.4064)
			(stroke
				(width 0.1524)
				(type default)
			)
			(layer "B.SilkS")
		)
		(fp_line
			(start -0.7874 -0.4064)
			(end -0.7874 0.4064)
			(stroke
				(width 0.1524)
				(type default)
			)
			(layer "B.SilkS")
		)
		(fp_line
			(start 0.7874 -0.4064)
			(end -0.7874 -0.4064)
			(stroke
				(width 0.1524)
				(type default)
			)
			(layer "B.SilkS")
		)
		(fp_line
			(start -0.67945 0.3048)
			(end -0.120396 0.3048)
			(stroke
				(width 0.1)
				(type default)
			)
			(layer "B.Fab")
		)
		(fp_line
			(start -0.120396 0.3048)
			(end -0.120396 0.2794)
			(stroke
				(width 0.1)
				(type default)
			)
			(layer "B.Fab")
		)
		(fp_line
			(start 0.12065 0.3048)
			(end 0.67945 0.3048)
			(stroke
				(width 0.1)
				(type default)
			)
			(layer "B.Fab")
		)
		(fp_line
			(start 0.67945 0.3048)
			(end 0.67945 -0.305054)
			(stroke
				(width 0.1)
				(type default)
			)
			(layer "B.Fab")
		)
		(fp_line
			(start -0.120396 0.2794)
			(end 0.12065 0.2794)
			(stroke
				(width 0.1)
				(type default)
			)
			(layer "B.Fab")
		)
		(fp_line
			(start 0.12065 0.2794)
			(end 0.12065 0.3048)
			(stroke
				(width 0.1)
				(type default)
			)
			(layer "B.Fab")
		)
		(fp_line
			(start -0.12065 -0.2794)
			(end -0.12065 -0.3048)
			(stroke
				(width 0.1)
				(type default)
			)
			(layer "B.Fab")
		)
		(fp_line
			(start 0.12065 -0.2794)
			(end -0.12065 -0.2794)
			(stroke
				(width 0.1)
				(type default)
			)
			(layer "B.Fab")
		)
		(fp_line
			(start -0.67945 -0.3048)
			(end -0.67945 0.3048)
			(stroke
				(width 0.1)
				(type default)
			)
			(layer "B.Fab")
		)
		(fp_line
			(start -0.12065 -0.3048)
			(end -0.67945 -0.3048)
			(stroke
				(width 0.1)
				(type default)
			)
			(layer "B.Fab")
		)
		(fp_line
			(start 0.12065 -0.305054)
			(end 0.12065 -0.2794)
			(stroke
				(width 0.1)
				(type default)
			)
			(layer "B.Fab")
		)
		(fp_line
			(start 0.67945 -0.305054)
			(end 0.12065 -0.305054)
			(stroke
				(width 0.1)
				(type default)
			)
			(layer "B.Fab")
		)
		(pad "1" smd circle
			(at 0.40005 0 90)
			(size 0 0)
			(layers "B.Cu" "B.Mask" "B.Paste")
			(net "P12V_BRICK_PWRGD_R_N")
		)
		(pad "2" smd circle
			(at -0.40005 0 90)
			(size 0 0)
			(layers "B.Cu" "B.Mask" "B.Paste")
			(net "P12V_BRICK_PWRGD_N")
		)
	)
	(footprint ""
		(layer "B.Cu")
		(at 289.306 -49.911)
		(property "Reference" "PR10"
			(at 0 0 0)
			(layer "B.SilkS")
			(hide yes)
			(effects
				(font
					(size 1.27 1.27)
				)
				(justify mirror)
			)
		)
		(property "Value" ""
			(at 0 0 0)
			(layer "B.Fab")
			(effects
				(font
					(size 1.27 1.27)
				)
				(justify mirror)
			)
		)
		(duplicate_pad_numbers_are_jumpers no)
		(fp_line
			(start -0.7874 -0.4064)
			(end -0.7874 0.4064)
			(stroke
				(width 0.1524)
				(type default)
			)
			(layer "B.SilkS")
		)
		(fp_line
			(start -0.7874 0.4064)
			(end 0.7874 0.4064)
			(stroke
				(width 0.1524)
				(type default)
			)
			(layer "B.SilkS")
		)
		(fp_line
			(start 0.7874 -0.4064)
			(end -0.7874 -0.4064)
			(stroke
				(width 0.1524)
				(type default)
			)
			(layer "B.SilkS")
		)
		(fp_line
			(start 0.7874 0.4064)
			(end 0.7874 -0.4064)
			(stroke
				(width 0.1524)
				(type default)
			)
			(layer "B.SilkS")
		)
		(fp_line
			(start -0.67945 -0.3048)
			(end -0.67945 0.3048)
			(stroke
				(width 0.1)
				(type default)
			)
			(layer "B.Fab")
		)
		(fp_line
			(start -0.67945 0.3048)
			(end -0.120396 0.3048)
			(stroke
				(width 0.1)
				(type default)
			)
			(layer "B.Fab")
		)
		(fp_line
			(start -0.12065 -0.3048)
			(end -0.67945 -0.3048)
			(stroke
				(width 0.1)
				(type default)
			)
			(layer "B.Fab")
		)
		(fp_line
			(start -0.12065 -0.2794)
			(end -0.12065 -0.3048)
			(stroke
				(width 0.1)
				(type default)
			)
			(layer "B.Fab")
		)
		(fp_line
			(start -0.120396 0.2794)
			(end 0.12065 0.2794)
			(stroke
				(width 0.1)
				(type default)
			)
			(layer "B.Fab")
		)
		(fp_line
			(start -0.120396 0.3048)
			(end -0.120396 0.2794)
			(stroke
				(width 0.1)
				(type default)
			)
			(layer "B.Fab")
		)
		(fp_line
			(start 0.12065 -0.305054)
			(end 0.12065 -0.2794)
			(stroke
				(width 0.1)
				(type default)
			)
			(layer "B.Fab")
		)
		(fp_line
			(start 0.12065 -0.2794)
			(end -0.12065 -0.2794)
			(stroke
				(width 0.1)
				(type default)
			)
			(layer "B.Fab")
		)
		(fp_line
			(start 0.12065 0.2794)
			(end 0.12065 0.3048)
			(stroke
				(width 0.1)
				(type default)
			)
			(layer "B.Fab")
		)
		(fp_line
			(start 0.12065 0.3048)
			(end 0.67945 0.3048)
			(stroke
				(width 0.1)
				(type default)
			)
			(layer "B.Fab")
		)
		(fp_line
			(start 0.67945 -0.305054)
			(end 0.12065 -0.305054)
			(stroke
				(width 0.1)
				(type default)
			)
			(layer "B.Fab")
		)
		(fp_line
			(start 0.67945 0.3048)
			(end 0.67945 -0.305054)
			(stroke
				(width 0.1)
				(type default)
			)
			(layer "B.Fab")
		)
		(pad "1" smd circle
			(at 0.40005 0 180)
			(size 0 0)
			(layers "B.Cu" "B.Mask" "B.Paste")
			(net "P52V_HS1_UVLO_EN")
		)
		(pad "2" smd circle
			(at -0.40005 0 180)
			(size 0 0)
			(layers "B.Cu" "B.Mask" "B.Paste")
			(net "GND_FIELD_SIGNAL")
		)
	)
	(footprint ""
		(layer "B.Cu")
		(at 179.065174 -77.597 180)
		(property "Reference" "C73"
			(at 0 0 0)
			(layer "B.SilkS")
			(hide yes)
			(effects
				(font
					(size 1.27 1.27)
				)
				(justify mirror)
			)
		)
		(property "Value" ""
			(at 0 0 0)
			(layer "B.Fab")
			(effects
				(font
					(size 1.27 1.27)
				)
				(justify mirror)
			)
		)
		(duplicate_pad_numbers_are_jumpers no)
		(fp_line
			(start 0.7874 0.4064)
			(end 0.7874 -0.4064)
			(stroke
				(width 0.1524)
				(type default)
			)
			(layer "B.SilkS")
		)
		(fp_line
			(start 0.7874 -0.4064)
			(end -0.7874 -0.4064)
			(stroke
				(width 0.1524)
				(type default)
			)
			(layer "B.SilkS")
		)
		(fp_line
			(start -0.7874 0.4064)
			(end 0.7874 0.4064)
			(stroke
				(width 0.1524)
				(type default)
			)
			(layer "B.SilkS")
		)
		(fp_line
			(start -0.7874 -0.4064)
			(end -0.7874 0.4064)
			(stroke
				(width 0.1524)
				(type default)
			)
			(layer "B.SilkS")
		)
		(fp_line
			(start 0.67945 0.3048)
			(end 0.67945 -0.305054)
			(stroke
				(width 0.1)
				(type default)
			)
			(layer "B.Fab")
		)
		(fp_line
			(start 0.67945 -0.305054)
			(end 0.12065 -0.305054)
			(stroke
				(width 0.1)
				(type default)
			)
			(layer "B.Fab")
		)
		(fp_line
			(start 0.12065 0.3048)
			(end 0.67945 0.3048)
			(stroke
				(width 0.1)
				(type default)
			)
			(layer "B.Fab")
		)
		(fp_line
			(start 0.12065 0.2794)
			(end 0.12065 0.3048)
			(stroke
				(width 0.1)
				(type default)
			)
			(layer "B.Fab")
		)
		(fp_line
			(start 0.12065 -0.2794)
			(end -0.12065 -0.2794)
			(stroke
				(width 0.1)
				(type default)
			)
			(layer "B.Fab")
		)
		(fp_line
			(start 0.12065 -0.305054)
			(end 0.12065 -0.2794)
			(stroke
				(width 0.1)
				(type default)
			)
			(layer "B.Fab")
		)
		(fp_line
			(start -0.120396 0.3048)
			(end -0.120396 0.2794)
			(stroke
				(width 0.1)
				(type default)
			)
			(layer "B.Fab")
		)
		(fp_line
			(start -0.120396 0.2794)
			(end 0.12065 0.2794)
			(stroke
				(width 0.1)
				(type default)
			)
			(layer "B.Fab")
		)
		(fp_line
			(start -0.12065 -0.2794)
			(end -0.12065 -0.3048)
			(stroke
				(width 0.1)
				(type default)
			)
			(layer "B.Fab")
		)
		(fp_line
			(start -0.12065 -0.3048)
			(end -0.67945 -0.3048)
			(stroke
				(width 0.1)
				(type default)
			)
			(layer "B.Fab")
		)
		(fp_line
			(start -0.67945 0.3048)
			(end -0.120396 0.3048)
			(stroke
				(width 0.1)
				(type default)
			)
			(layer "B.Fab")
		)
		(fp_line
			(start -0.67945 -0.3048)
			(end -0.67945 0.3048)
			(stroke
				(width 0.1)
				(type default)
			)
			(layer "B.Fab")
		)
		(pad "1" smd circle
			(at 0.40005 0)
			(size 0 0)
			(layers "B.Cu" "B.Mask" "B.Paste")
			(net "SMB_P52V_VPDB_SCL")
		)
		(pad "2" smd circle
			(at -0.40005 0)
			(size 0 0)
			(layers "B.Cu" "B.Mask" "B.Paste")
			(net "GND")
		)
	)
	(footprint ""
		(layer "B.Cu")
		(at 275.169122 -87.361522)
		(property "Reference" "PC565"
			(at 0 0 0)
			(layer "B.SilkS")
			(hide yes)
			(effects
				(font
					(size 1.27 1.27)
				)
				(justify mirror)
			)
		)
		(property "Value" ""
			(at 0 0 0)
			(layer "B.Fab")
			(effects
				(font
					(size 1.27 1.27)
				)
				(justify mirror)
			)
		)
		(duplicate_pad_numbers_are_jumpers no)
		(fp_line
			(start -1.2954 -0.5842)
			(end -1.2954 0.5842)
			(stroke
				(width 0.1524)
				(type default)
			)
			(layer "B.SilkS")
		)
		(fp_line
			(start -1.2954 0.5842)
			(end 1.2954 0.5842)
			(stroke
				(width 0.1524)
				(type default)
			)
			(layer "B.SilkS")
		)
		(fp_line
			(start 1.2954 -0.5842)
			(end -1.2954 -0.5842)
			(stroke
				(width 0.1524)
				(type default)
			)
			(layer "B.SilkS")
		)
		(fp_line
			(start 1.2954 0.5842)
			(end 1.2954 -0.5842)
			(stroke
				(width 0.1524)
				(type default)
			)
			(layer "B.SilkS")
		)
		(fp_line
			(start -1.1938 -0.4064)
			(end -1.1938 0.4064)
			(stroke
				(width 0.1)
				(type default)
			)
			(layer "B.Fab")
		)
		(fp_line
			(start -1.1938 0.4064)
			(end -0.8636 0.4064)
			(stroke
				(width 0.1)
				(type default)
			)
			(layer "B.Fab")
		)
		(fp_line
			(start -0.8636 -0.4572)
			(end -0.8636 -0.4064)
			(stroke
				(width 0.1)
				(type default)
			)
			(layer "B.Fab")
		)
		(fp_line
			(start -0.8636 -0.4064)
			(end -1.1938 -0.4064)
			(stroke
				(width 0.1)
				(type default)
			)
			(layer "B.Fab")
		)
		(fp_line
			(start -0.8636 0.4064)
			(end -0.8636 0.4572)
			(stroke
				(width 0.1)
				(type default)
			)
			(layer "B.Fab")
		)
		(fp_line
			(start -0.8636 0.4572)
			(end 0.8636 0.4572)
			(stroke
				(width 0.1)
				(type default)
			)
			(layer "B.Fab")
		)
		(fp_line
			(start 0.8636 -0.4572)
			(end -0.8636 -0.4572)
			(stroke
				(width 0.1)
				(type default)
			)
			(layer "B.Fab")
		)
		(fp_line
			(start 0.8636 -0.4064)
			(end 0.8636 -0.4572)
			(stroke
				(width 0.1)
				(type default)
			)
			(layer "B.Fab")
		)
		(fp_line
			(start 0.8636 0.4064)
			(end 1.1938 0.4064)
			(stroke
				(width 0.1)
				(type default)
			)
			(layer "B.Fab")
		)
		(fp_line
			(start 0.8636 0.4572)
			(end 0.8636 0.4064)
			(stroke
				(width 0.1)
				(type default)
			)
			(layer "B.Fab")
		)
		(fp_line
			(start 1.1938 -0.4064)
			(end 0.8636 -0.4064)
			(stroke
				(width 0.1)
				(type default)
			)
			(layer "B.Fab")
		)
		(fp_line
			(start 1.1938 0.4064)
			(end 1.1938 -0.4064)
			(stroke
				(width 0.1)
				(type default)
			)
			(layer "B.Fab")
		)
		(pad "1" smd rect
			(at 0.7366 0 270)
			(size 0.7112 0.8128)
			(layers "B.Cu" "B.Mask" "B.Paste")
			(net "P52V_HS1_4287_GATE2_RC")
		)
		(pad "2" smd rect
			(at -0.7366 0 270)
			(size 0.7112 0.8128)
			(layers "B.Cu" "B.Mask" "B.Paste")
			(net "P52V_HS")
		)
	)
)
